(kicad_pcb
	(version 20260206)
	(generator "pcbnew")
	(generator_version "10.0")
	(general
		(thickness 1.6)
		(legacy_teardrops no)
	)
	(paper "A4")
	(title_block
		(title "Wiwynn_Tioga_Pass_MB.brd")
		(comment 1 "Tioga Pass / footprints 3507-3514 of 4770")
	)
	(layers
		(0 "F.Cu" signal "TOP")
		(4 "In1.Cu" signal "L2GND")
		(6 "In2.Cu" signal "L3")
		(8 "In3.Cu" signal "L4GND")
		(10 "In4.Cu" signal "L5")
		(12 "In5.Cu" signal "L6GND")
		(14 "In6.Cu" signal "L7VCC")
		(16 "In7.Cu" signal "L8VCC")
		(18 "In8.Cu" signal "L9GND")
		(20 "In9.Cu" signal "L10")
		(22 "In10.Cu" signal "L11GND")
		(24 "In11.Cu" signal "L12")
		(26 "In12.Cu" signal "L13GND")
		(2 "B.Cu" signal "BOTTOM")
		(9 "F.Adhes" user "F.Adhesive")
		(11 "B.Adhes" user "B.Adhesive")
		(13 "F.Paste" user "Package Geometry/Pastemask Top")
		(15 "B.Paste" user "Package Geometry/Pastemask Bottom")
		(5 "F.SilkS" user "Ref Des/Silkscreen Top")
		(7 "B.SilkS" user "Ref Des/Silkscreen Bottom")
		(1 "F.Mask" user "Board Geometry/Soldermask Top")
		(3 "B.Mask" user "Board Geometry/Soldermask Bottom")
		(17 "Dwgs.User" user "User.Drawings")
		(19 "Cmts.User" user "User.Comments")
		(21 "Eco1.User" user "User.Eco1")
		(23 "Eco2.User" user "User.Eco2")
		(25 "Edge.Cuts" user "Board Geometry/Outline")
		(27 "Margin" user)
		(31 "F.CrtYd" user "Package Geometry/Place Bound Top")
		(29 "B.CrtYd" user "Package Geometry/Place Bound Bottom")
		(35 "F.Fab" user "Ref Des/Assembly Top")
		(33 "B.Fab" user "Ref Des/Assembly Bottom")
	)
	(footprint ""
		(layer "B.Cu")
		(at 343.248234 -130.120898 90)
		(property "Reference" "R7B20"
			(at 0 0 90)
			(layer "B.SilkS")
			(hide yes)
			(effects
				(font
					(size 1.27 1.27)
				)
				(justify mirror)
			)
		)
		(property "Value" ""
			(at 0 0 90)
			(layer "B.Fab")
			(effects
				(font
					(size 1.27 1.27)
				)
				(justify mirror)
			)
		)
		(duplicate_pad_numbers_are_jumpers no)
		(fp_poly
			(pts
				(xy 0.2794 -0.1016) (xy -0.2794 -0.1016) (xy -0.2794 0.9906) (xy 0.2794 0.9906)
			)
			(stroke
				(width 0)
				(type default)
			)
			(fill no)
			(layer "B.CrtYd")
		)
		(fp_line
			(start 0.2794 -0.1016)
			(end 0.2794 0.9906)
			(stroke
				(width 0.1)
				(type default)
			)
			(layer "B.Fab")
		)
		(fp_line
			(start -0.2794 -0.1016)
			(end 0.2794 -0.1016)
			(stroke
				(width 0.1)
				(type default)
			)
			(layer "B.Fab")
		)
		(fp_line
			(start 0.2794 0.9906)
			(end -0.2794 0.9906)
			(stroke
				(width 0.1)
				(type default)
			)
			(layer "B.Fab")
		)
		(fp_line
			(start -0.2794 0.9906)
			(end -0.2794 -0.1016)
			(stroke
				(width 0.1)
				(type default)
			)
			(layer "B.Fab")
		)
		(pad "1" smd rect
			(at 0 0 270)
			(size 0.508 0.508)
			(layers "B.Cu" "B.Mask" "B.Paste")
			(net "GND")
		)
		(pad "2" smd rect
			(at 0 0.889 270)
			(size 0.508 0.508)
			(layers "B.Cu" "B.Mask" "B.Paste")
			(net "AGND_PVPP_DEF")
		)
		(zone
			(layer "B.Cu")
			(hatch none 0.5)
			(connect_pads
				(clearance 0)
			)
			(min_thickness 0.25)
			(keepout
				(tracks allowed)
				(vias not_allowed)
				(pads allowed)
				(copperpour not_allowed)
				(footprints allowed)
			)
			(placement
				(enabled no)
				(sheetname "")
			)
			(fill
				(thermal_gap 0.5)
				(thermal_bridge_width 0.5)
				(island_removal_mode 0)
			)
			(polygon
				(pts
					(xy 343.502234 -130.374898) (xy 343.502234 -129.866898) (xy 343.883234 -129.866898) (xy 343.883234 -130.374898)
				)
			)
		)
		(zone
			(layer "B.Cu")
			(hatch none 0.5)
			(connect_pads
				(clearance 0)
			)
			(min_thickness 0.25)
			(keepout
				(tracks not_allowed)
				(vias allowed)
				(pads allowed)
				(copperpour not_allowed)
				(footprints allowed)
			)
			(placement
				(enabled no)
				(sheetname "")
			)
			(fill
				(thermal_gap 0.5)
				(thermal_bridge_width 0.5)
				(island_removal_mode 0)
			)
			(polygon
				(pts
					(xy 343.883234 -130.374898) (xy 343.883234 -129.866898) (xy 343.502234 -129.866898) (xy 343.502234 -130.374898)
				)
			)
		)
	)
	(footprint ""
		(layer "B.Cu")
		(at 405.219408 -94.517718 -90)
		(property "Reference" "R2U30"
			(at 0 0 90)
			(layer "B.SilkS")
			(hide yes)
			(effects
				(font
					(size 1.27 1.27)
				)
				(justify mirror)
			)
		)
		(property "Value" ""
			(at 0 0 90)
			(layer "B.Fab")
			(effects
				(font
					(size 1.27 1.27)
				)
				(justify mirror)
			)
		)
		(duplicate_pad_numbers_are_jumpers no)
		(fp_poly
			(pts
				(xy 0.2794 -0.1016) (xy -0.2794 -0.1016) (xy -0.2794 0.9906) (xy 0.2794 0.9906)
			)
			(stroke
				(width 0)
				(type default)
			)
			(fill no)
			(layer "B.CrtYd")
		)
		(fp_line
			(start -0.2794 0.9906)
			(end -0.2794 -0.1016)
			(stroke
				(width 0.1)
				(type default)
			)
			(layer "B.Fab")
		)
		(fp_line
			(start 0.2794 0.9906)
			(end -0.2794 0.9906)
			(stroke
				(width 0.1)
				(type default)
			)
			(layer "B.Fab")
		)
		(fp_line
			(start -0.2794 -0.1016)
			(end 0.2794 -0.1016)
			(stroke
				(width 0.1)
				(type default)
			)
			(layer "B.Fab")
		)
		(fp_line
			(start 0.2794 -0.1016)
			(end 0.2794 0.9906)
			(stroke
				(width 0.1)
				(type default)
			)
			(layer "B.Fab")
		)
		(pad "1" smd rect
			(at 0 0 90)
			(size 0.508 0.508)
			(layers "B.Cu" "B.Mask" "B.Paste")
			(net "P3V3_STBY")
		)
		(pad "2" smd rect
			(at 0 0.889 90)
			(size 0.508 0.508)
			(layers "B.Cu" "B.Mask" "B.Paste")
			(net "FM_UV_ADR_TRIGGER_EN")
		)
		(zone
			(layer "B.Cu")
			(hatch none 0.5)
			(connect_pads
				(clearance 0)
			)
			(min_thickness 0.25)
			(keepout
				(tracks not_allowed)
				(vias allowed)
				(pads allowed)
				(copperpour not_allowed)
				(footprints allowed)
			)
			(placement
				(enabled no)
				(sheetname "")
			)
			(fill
				(thermal_gap 0.5)
				(thermal_bridge_width 0.5)
				(island_removal_mode 0)
			)
			(polygon
				(pts
					(xy 404.584408 -94.263718) (xy 404.584408 -94.771718) (xy 404.965408 -94.771718) (xy 404.965408 -94.263718)
				)
			)
		)
		(zone
			(layer "B.Cu")
			(hatch none 0.5)
			(connect_pads
				(clearance 0)
			)
			(min_thickness 0.25)
			(keepout
				(tracks allowed)
				(vias not_allowed)
				(pads allowed)
				(copperpour not_allowed)
				(footprints allowed)
			)
			(placement
				(enabled no)
				(sheetname "")
			)
			(fill
				(thermal_gap 0.5)
				(thermal_bridge_width 0.5)
				(island_removal_mode 0)
			)
			(polygon
				(pts
					(xy 404.965408 -94.263718) (xy 404.965408 -94.771718) (xy 404.584408 -94.771718) (xy 404.584408 -94.263718)
				)
			)
		)
	)
	(footprint ""
		(layer "B.Cu")
		(at 372.676166 -61.098938 90)
		(property "Reference" "R3R1"
			(at 0 0 90)
			(layer "B.SilkS")
			(hide yes)
			(effects
				(font
					(size 1.27 1.27)
				)
				(justify mirror)
			)
		)
		(property "Value" ""
			(at 0 0 90)
			(layer "B.Fab")
			(effects
				(font
					(size 1.27 1.27)
				)
				(justify mirror)
			)
		)
		(duplicate_pad_numbers_are_jumpers no)
		(fp_poly
			(pts
				(xy 0.2794 -0.1016) (xy -0.2794 -0.1016) (xy -0.2794 0.9906) (xy 0.2794 0.9906)
			)
			(stroke
				(width 0)
				(type default)
			)
			(fill no)
			(layer "B.CrtYd")
		)
		(fp_line
			(start 0.2794 -0.1016)
			(end 0.2794 0.9906)
			(stroke
				(width 0.1)
				(type default)
			)
			(layer "B.Fab")
		)
		(fp_line
			(start -0.2794 -0.1016)
			(end 0.2794 -0.1016)
			(stroke
				(width 0.1)
				(type default)
			)
			(layer "B.Fab")
		)
		(fp_line
			(start 0.2794 0.9906)
			(end -0.2794 0.9906)
			(stroke
				(width 0.1)
				(type default)
			)
			(layer "B.Fab")
		)
		(fp_line
			(start -0.2794 0.9906)
			(end -0.2794 -0.1016)
			(stroke
				(width 0.1)
				(type default)
			)
			(layer "B.Fab")
		)
		(pad "1" smd rect
			(at 0 0 270)
			(size 0.508 0.508)
			(layers "B.Cu" "B.Mask" "B.Paste")
			(net "PD_GTL2104_DIR_1")
		)
		(pad "2" smd rect
			(at 0 0.889 270)
			(size 0.508 0.508)
			(layers "B.Cu" "B.Mask" "B.Paste")
			(net "GND")
		)
		(zone
			(layer "B.Cu")
			(hatch none 0.5)
			(connect_pads
				(clearance 0)
			)
			(min_thickness 0.25)
			(keepout
				(tracks allowed)
				(vias not_allowed)
				(pads allowed)
				(copperpour not_allowed)
				(footprints allowed)
			)
			(placement
				(enabled no)
				(sheetname "")
			)
			(fill
				(thermal_gap 0.5)
				(thermal_bridge_width 0.5)
				(island_removal_mode 0)
			)
			(polygon
				(pts
					(xy 372.930166 -61.352938) (xy 372.930166 -60.844938) (xy 373.311166 -60.844938) (xy 373.311166 -61.352938)
				)
			)
		)
		(zone
			(layer "B.Cu")
			(hatch none 0.5)
			(connect_pads
				(clearance 0)
			)
			(min_thickness 0.25)
			(keepout
				(tracks not_allowed)
				(vias allowed)
				(pads allowed)
				(copperpour not_allowed)
				(footprints allowed)
			)
			(placement
				(enabled no)
				(sheetname "")
			)
			(fill
				(thermal_gap 0.5)
				(thermal_bridge_width 0.5)
				(island_removal_mode 0)
			)
			(polygon
				(pts
					(xy 373.311166 -61.352938) (xy 373.311166 -60.844938) (xy 372.930166 -60.844938) (xy 372.930166 -61.352938)
				)
			)
		)
	)
	(footprint ""
		(layer "B.Cu")
		(at 166.68877 2.209546 90)
		(property "Reference" "R6U13"
			(at 0 0 90)
			(layer "B.SilkS")
			(hide yes)
			(effects
				(font
					(size 1.27 1.27)
				)
				(justify mirror)
			)
		)
		(property "Value" ""
			(at 0 0 90)
			(layer "B.Fab")
			(effects
				(font
					(size 1.27 1.27)
				)
				(justify mirror)
			)
		)
		(duplicate_pad_numbers_are_jumpers no)
		(fp_poly
			(pts
				(xy 0.2794 -0.1016) (xy -0.2794 -0.1016) (xy -0.2794 0.9906) (xy 0.2794 0.9906)
			)
			(stroke
				(width 0)
				(type default)
			)
			(fill no)
			(layer "B.CrtYd")
		)
		(fp_line
			(start 0.2794 -0.1016)
			(end 0.2794 0.9906)
			(stroke
				(width 0.1)
				(type default)
			)
			(layer "B.Fab")
		)
		(fp_line
			(start -0.2794 -0.1016)
			(end 0.2794 -0.1016)
			(stroke
				(width 0.1)
				(type default)
			)
			(layer "B.Fab")
		)
		(fp_line
			(start 0.2794 0.9906)
			(end -0.2794 0.9906)
			(stroke
				(width 0.1)
				(type default)
			)
			(layer "B.Fab")
		)
		(fp_line
			(start -0.2794 0.9906)
			(end -0.2794 -0.1016)
			(stroke
				(width 0.1)
				(type default)
			)
			(layer "B.Fab")
		)
		(pad "1" smd rect
			(at 0 0 270)
			(size 0.508 0.508)
			(layers "B.Cu" "B.Mask" "B.Paste")
			(net "SMB_DDR_GHJ_VPP_SCL_R")
		)
		(pad "2" smd rect
			(at 0 0.889 270)
			(size 0.508 0.508)
			(layers "B.Cu" "B.Mask" "B.Paste")
			(net "SMB_DDR_GHJ_VPP_SCL")
		)
		(zone
			(layer "B.Cu")
			(hatch none 0.5)
			(connect_pads
				(clearance 0)
			)
			(min_thickness 0.25)
			(keepout
				(tracks allowed)
				(vias not_allowed)
				(pads allowed)
				(copperpour not_allowed)
				(footprints allowed)
			)
			(placement
				(enabled no)
				(sheetname "")
			)
			(fill
				(thermal_gap 0.5)
				(thermal_bridge_width 0.5)
				(island_removal_mode 0)
			)
			(polygon
				(pts
					(xy 166.94277 1.955546) (xy 166.94277 2.463546) (xy 167.32377 2.463546) (xy 167.32377 1.955546)
				)
			)
		)
		(zone
			(layer "B.Cu")
			(hatch none 0.5)
			(connect_pads
				(clearance 0)
			)
			(min_thickness 0.25)
			(keepout
				(tracks not_allowed)
				(vias allowed)
				(pads allowed)
				(copperpour not_allowed)
				(footprints allowed)
			)
			(placement
				(enabled no)
				(sheetname "")
			)
			(fill
				(thermal_gap 0.5)
				(thermal_bridge_width 0.5)
				(island_removal_mode 0)
			)
			(polygon
				(pts
					(xy 167.32377 1.955546) (xy 167.32377 2.463546) (xy 166.94277 2.463546) (xy 166.94277 1.955546)
				)
			)
		)
	)
	(footprint ""
		(layer "B.Cu")
		(at 499.995698 -55.370222)
		(property "Reference" "C30W5"
			(at 0 0 0)
			(layer "B.SilkS")
			(hide yes)
			(effects
				(font
					(size 1.27 1.27)
				)
				(justify mirror)
			)
		)
		(property "Value" "*"
			(at 0.0762 -6.2357 0)
			(unlocked yes)
			(layer "B.Fab")
			(hide yes)
			(effects
				(font
					(size 1.27 1.016)
					(thickness 0.1524)
				)
				(justify mirror)
			)
		)
		(property "Device Type" "SC22U16V5MX-4-GP_SMD-BCG5-SC22A"
			(at 0.0762 -8.2677 0)
			(unlocked yes)
			(layer "B.Fab")
			(hide yes)
			(effects
				(font
					(size 1.27 1.016)
					(thickness 0.1524)
				)
				(justify mirror)
			)
		)
		(duplicate_pad_numbers_are_jumpers no)
		(fp_line
			(start -0.635 0)
			(end 0.635 0)
			(stroke
				(width 0.508)
				(type default)
			)
			(layer "B.SilkS")
		)
		(fp_rect
			(start 0.9652 1.778)
			(end -0.9652 -1.778)
			(stroke
				(width 0)
				(type default)
			)
			(fill no)
			(layer "B.CrtYd")
		)
		(fp_poly
			(pts
				(xy 0.9652 -1.778) (xy -0.9652 -1.778) (xy -0.9652 1.778) (xy 0.9652 1.778)
			)
			(stroke
				(width 0)
				(type default)
			)
			(fill no)
			(layer "B.Fab")
		)
		(pad "1" smd rect
			(at 0 -0.9652 180)
			(size 1.397 1.143)
			(layers "B.Cu" "B.Mask" "B.Paste")
			(net "P5V_STBY_USBC")
		)
		(pad "2" smd rect
			(at 0 0.9652 180)
			(size 1.397 1.143)
			(layers "B.Cu" "B.Mask" "B.Paste")
			(net "GND")
		)
	)
	(footprint ""
		(layer "B.Cu")
		(at 44.97578 -30.7975)
		(property "Reference" ""
			(at 0 0 0)
			(layer "B.SilkS")
			(hide yes)
			(effects
				(font
					(size 1.27 1.27)
				)
				(justify mirror)
			)
		)
		(property "Value" ""
			(at 0 0 0)
			(layer "B.Fab")
			(effects
				(font
					(size 1.27 1.27)
				)
				(justify mirror)
			)
		)
		(duplicate_pad_numbers_are_jumpers no)
		(fp_poly
			(pts
				(arc
					(start 2.032 0)
					(mid -2.032 0)
					(end 2.032 0)
				)
			)
			(stroke
				(width 0)
				(type default)
			)
			(fill no)
			(layer "B.CrtYd")
		)
		(pad "1" smd circle
			(at 0 0 180)
			(size 1.016 1.016)
			(layers "B.Cu" "B.Mask" "B.Paste")
			(net "Net_386")
		)
		(zone
			(layer "B.Cu")
			(hatch none 0.5)
			(connect_pads
				(clearance 0)
			)
			(min_thickness 0.25)
			(keepout
				(tracks not_allowed)
				(vias allowed)
				(pads allowed)
				(copperpour not_allowed)
				(footprints allowed)
			)
			(placement
				(enabled no)
				(sheetname "")
			)
			(fill
				(thermal_gap 0.5)
				(thermal_bridge_width 0.5)
				(island_removal_mode 0)
			)
			(polygon
				(pts
					(arc
						(start 46.49978 -30.7975)
						(mid 43.45178 -30.7975)
						(end 46.49978 -30.7975)
					)
				)
			)
		)
	)
	(footprint ""
		(layer "B.Cu")
		(at 488.2515 -43.5864 -90)
		(property "Reference" "C1R20"
			(at 0 0 90)
			(layer "B.SilkS")
			(hide yes)
			(effects
				(font
					(size 1.27 1.27)
				)
				(justify mirror)
			)
		)
		(property "Value" ""
			(at 0 0 90)
			(layer "B.Fab")
			(effects
				(font
					(size 1.27 1.27)
				)
				(justify mirror)
			)
		)
		(duplicate_pad_numbers_are_jumpers no)
		(fp_poly
			(pts
				(xy -0.3048 -0.1016) (xy -0.3048 0.9906) (xy 0.3048 0.9906) (xy 0.3048 -0.1016)
			)
			(stroke
				(width 0)
				(type default)
			)
			(fill no)
			(layer "B.CrtYd")
		)
		(fp_line
			(start -0.3048 0.9906)
			(end -0.3048 -0.1016)
			(stroke
				(width 0.1)
				(type default)
			)
			(layer "B.Fab")
		)
		(fp_line
			(start 0.3048 0.9906)
			(end -0.3048 0.9906)
			(stroke
				(width 0.1)
				(type default)
			)
			(layer "B.Fab")
		)
		(fp_line
			(start -0.3048 -0.1016)
			(end 0.3048 -0.1016)
			(stroke
				(width 0.1)
				(type default)
			)
			(layer "B.Fab")
		)
		(fp_line
			(start 0.3048 -0.1016)
			(end 0.3048 0.9906)
			(stroke
				(width 0.1)
				(type default)
			)
			(layer "B.Fab")
		)
		(pad "1" smd rect
			(at 0 0 90)
			(size 0.508 0.508)
			(layers "B.Cu" "B.Mask" "B.Paste")
			(net "P3V3_STBY")
		)
		(pad "2" smd rect
			(at 0 0.889 90)
			(size 0.508 0.508)
			(layers "B.Cu" "B.Mask" "B.Paste")
			(net "GND")
		)
		(zone
			(layer "B.Cu")
			(hatch none 0.5)
			(connect_pads
				(clearance 0)
			)
			(min_thickness 0.25)
			(keepout
				(tracks not_allowed)
				(vias allowed)
				(pads allowed)
				(copperpour not_allowed)
				(footprints allowed)
			)
			(placement
				(enabled no)
				(sheetname "")
			)
			(fill
				(thermal_gap 0.5)
				(thermal_bridge_width 0.5)
				(island_removal_mode 0)
			)
			(polygon
				(pts
					(xy 487.6165 -43.3324) (xy 487.6165 -43.8404) (xy 487.9975 -43.8404) (xy 487.9975 -43.3324)
				)
			)
		)
		(zone
			(layer "B.Cu")
			(hatch none 0.5)
			(connect_pads
				(clearance 0)
			)
			(min_thickness 0.25)
			(keepout
				(tracks allowed)
				(vias not_allowed)
				(pads allowed)
				(copperpour not_allowed)
				(footprints allowed)
			)
			(placement
				(enabled no)
				(sheetname "")
			)
			(fill
				(thermal_gap 0.5)
				(thermal_bridge_width 0.5)
				(island_removal_mode 0)
			)
			(polygon
				(pts
					(xy 487.9975 -43.3324) (xy 487.9975 -43.8404) (xy 487.6165 -43.8404) (xy 487.6165 -43.3324)
				)
			)
		)
	)
	(footprint ""
		(layer "B.Cu")
		(at 2.19456 -143.256 90)
		(property "Reference" "C1A11"
			(at 0 0 90)
			(layer "B.SilkS")
			(hide yes)
			(effects
				(font
					(size 1.27 1.27)
				)
				(justify mirror)
			)
		)
		(property "Value" "*"
			(at -1.1811 -2.8194 90)
			(unlocked yes)
			(layer "B.Fab")
			(hide yes)
			(effects
				(font
					(size 1.27 1.016)
					(thickness 0.1524)
				)
				(justify mirror)
			)
		)
		(property "Device Type" "SC1U10V2KX-4-GP_SMD-BCG6-SC1U1A"
			(at -1.1811 -4.3434 90)
			(unlocked yes)
			(layer "B.Fab")
			(hide yes)
			(effects
				(font
					(size 1.27 1.016)
					(thickness 0.1524)
				)
				(justify mirror)
			)
		)
		(duplicate_pad_numbers_are_jumpers no)
		(fp_rect
			(start 0.4318 0.9525)
			(end -0.4318 -0.9525)
			(stroke
				(width 0)
				(type default)
			)
			(fill no)
			(layer "B.CrtYd")
		)
		(fp_rect
			(start 0.4318 0.9525)
			(end -0.4318 -0.9525)
			(stroke
				(width 0)
				(type default)
			)
			(fill no)
			(layer "B.Fab")
		)
		(pad "1" smd custom
			(at 0 -0.4445 270)
			(size 0.1524 0.1524)
			(layers "B.Cu" "B.Mask" "B.Paste")
			(net "P5V_STBY")
			(options
				(clearance outline)
				(anchor circle)
			)
			(primitives
				(gr_poly
					(pts
						(arc
							(start 0.3048 0.2032)
							(mid 0.275042 0.275042)
							(end 0.2032 0.3048)
						)
						(arc
							(start -0.2032 0.3048)
							(mid -0.275042 0.275042)
							(end -0.3048 0.2032)
						)
						(arc
							(start -0.3048 -0.2032)
							(mid -0.275042 -0.275042)
							(end -0.2032 -0.3048)
						)
						(arc
							(start 0.2032 -0.3048)
							(mid 0.275042 -0.275042)
							(end 0.3048 -0.2032)
						)
					)
					(width 0)
					(fill yes)
				)
			)
		)
		(pad "2" smd custom
			(at 0 0.4445 270)
			(size 0.1524 0.1524)
			(layers "B.Cu" "B.Mask" "B.Paste")
			(net "GND")
			(options
				(clearance outline)
				(anchor circle)
			)
			(primitives
				(gr_poly
					(pts
						(arc
							(start 0.3048 0.2032)
							(mid 0.275042 0.275042)
							(end 0.2032 0.3048)
						)
						(arc
							(start -0.2032 0.3048)
							(mid -0.275042 0.275042)
							(end -0.3048 0.2032)
						)
						(arc
							(start -0.3048 -0.2032)
							(mid -0.275042 -0.275042)
							(end -0.2032 -0.3048)
						)
						(arc
							(start 0.2032 -0.3048)
							(mid 0.275042 -0.275042)
							(end 0.3048 -0.2032)
						)
					)
					(width 0)
					(fill yes)
				)
			)
		)
	)
)
